(kicad_pcb
	(version 20241229)
	(generator "pcbnew")
	(generator_version "9.0")
	(general
		(thickness 0.761)
		(legacy_teardrops no)
	)
	(paper "A4")
	(title_block
		(title " M.2 to OCuLink adapter")
		(date "2025-07-16")
		(rev "1.0.2")
		(company "Antmicro Ltd")
		(comment 1 "www.antmicro.com")
		(comment 9 "footprints 13-17 of 22")
	)
	(layers
		(0 "F.Cu" signal)
		(4 "In1.Cu" signal)
		(6 "In2.Cu" signal)
		(2 "B.Cu" signal)
		(9 "F.Adhes" user "F.Adhesive")
		(11 "B.Adhes" user "B.Adhesive")
		(13 "F.Paste" user)
		(15 "B.Paste" user)
		(5 "F.SilkS" user "F.Silkscreen")
		(7 "B.SilkS" user "B.Silkscreen")
		(1 "F.Mask" user)
		(3 "B.Mask" user)
		(17 "Dwgs.User" user "User.Drawings")
		(19 "Cmts.User" user "User.Comments")
		(21 "Eco1.User" user "User.Eco1")
		(23 "Eco2.User" user "User.Eco2")
		(25 "Edge.Cuts" user)
		(27 "Margin" user)
		(31 "F.CrtYd" user "F.Courtyard")
		(29 "B.CrtYd" user "B.Courtyard")
		(35 "F.Fab" user)
		(33 "B.Fab" user)
	)
	(footprint "antmicro-footprints:C_0402_1005Metric"
		(layer "B.Cu")
		(at 139.45 97.42 90)
		(descr "Capacitor SMD 0402")
		(tags "capacitor SMD 0402")
		(property "Reference" "C3"
			(at -2.36 -0.37 270)
			(layer "B.SilkS")
			(effects
				(font
					(size 0.7 0.7)
					(thickness 0.15)
				)
				(justify right top mirror)
			)
		)
		(property "Value" "C_100n_16V_X7R_0402"
			(at -1.022927 -2.155213 90)
			(layer "B.Fab")
			(effects
				(font
					(size 0.7 0.7)
					(thickness 0.15)
				)
				(justify right top mirror)
			)
		)
		(property "Datasheet" "https://www.kemet.com/en/us/capacitors/product/C0402C104J4RAC7411.html"
			(at 0 0 90)
			(layer "B.Fab")
			(hide yes)
			(effects
				(font
					(size 1.27 1.27)
					(thickness 0.15)
				)
				(justify mirror)
			)
		)
		(property "Description" "SMD Multilayer Ceramic Capacitor, 100nF, 50V, 0402, ±5%, X7R"
			(at 0 0 90)
			(layer "B.Fab")
			(hide yes)
			(effects
				(font
					(size 1.27 1.27)
					(thickness 0.15)
				)
				(justify mirror)
			)
		)
		(property "MPN" "C0402C104J4RAC7411"
			(at 0 0 270)
			(unlocked yes)
			(layer "B.Fab")
			(hide yes)
			(effects
				(font
					(size 1 1)
					(thickness 0.15)
				)
				(justify mirror)
			)
		)
		(property "Val" "100n"
			(at 0 0 270)
			(unlocked yes)
			(layer "B.Fab")
			(hide yes)
			(effects
				(font
					(size 1 1)
					(thickness 0.15)
				)
				(justify mirror)
			)
		)
		(property "Voltage" "16V"
			(at 0 0 270)
			(unlocked yes)
			(layer "B.Fab")
			(hide yes)
			(effects
				(font
					(size 1 1)
					(thickness 0.15)
				)
				(justify mirror)
			)
		)
		(property "Dielectric" "X7R"
			(at 0 0 270)
			(unlocked yes)
			(layer "B.Fab")
			(hide yes)
			(effects
				(font
					(size 1 1)
					(thickness 0.15)
				)
				(justify mirror)
			)
		)
		(property "Manufacturer" "KEMET"
			(at 0 0 270)
			(unlocked yes)
			(layer "B.Fab")
			(hide yes)
			(effects
				(font
					(size 1 1)
					(thickness 0.15)
				)
				(justify mirror)
			)
		)
		(property "License" "Apache-2.0"
			(at 0 0 270)
			(unlocked yes)
			(layer "B.Fab")
			(hide yes)
			(effects
				(font
					(size 1 1)
					(thickness 0.15)
				)
				(justify mirror)
			)
		)
		(property "Author" "Antmicro"
			(at 0 0 270)
			(unlocked yes)
			(layer "B.Fab")
			(hide yes)
			(effects
				(font
					(size 1 1)
					(thickness 0.15)
				)
				(justify mirror)
			)
		)
		(sheetname "/")
		(sheetfile "antmicro-m2-oculink-adapter-hw.kicad_sch")
		(attr smd)
		(fp_rect
			(start -0.925 0.47)
			(end 0.925 -0.47)
			(stroke
				(width 0.05)
				(type default)
			)
			(fill no)
			(layer "B.CrtYd")
		)
		(fp_line
			(start 0.504 -0.248)
			(end -0.494 -0.248)
			(stroke
				(width 0.15)
				(type solid)
			)
			(layer "B.Fab")
		)
		(fp_line
			(start -0.494 -0.248)
			(end -0.494 0.25)
			(stroke
				(width 0.15)
				(type solid)
			)
			(layer "B.Fab")
		)
		(fp_line
			(start 0.504 0.25)
			(end 0.504 -0.248)
			(stroke
				(width 0.15)
				(type solid)
			)
			(layer "B.Fab")
		)
		(fp_line
			(start -0.494 0.25)
			(end 0.504 0.25)
			(stroke
				(width 0.15)
				(type solid)
			)
			(layer "B.Fab")
		)
		(fp_text user "${REFERENCE}"
			(at -0.939 -4.599 90)
			(layer "B.Fab")
			(effects
				(font
					(size 0.7 0.7)
					(thickness 0.15)
				)
				(justify right top mirror)
			)
		)
		(fp_text user "Author: Antmicro"
			(at -0.939 -3.399 90)
			(layer "B.Fab")
			(effects
				(font
					(size 0.7 0.7)
					(thickness 0.15)
				)
				(justify right top mirror)
			)
		)
		(fp_text user "License: Apache-2.0"
			(at -0.939 -5.799 90)
			(layer "B.Fab")
			(effects
				(font
					(size 0.7 0.7)
					(thickness 0.15)
				)
				(justify right top mirror)
			)
		)
		(pad "1" smd roundrect
			(at -0.48 0 90)
			(size 0.59 0.64)
			(layers "B.Cu" "B.Mask" "B.Paste")
			(roundrect_rratio 0.25)
			(net 1 "GND")
			(pintype "passive")
		)
		(pad "2" smd roundrect
			(at 0.48 0 90)
			(size 0.59 0.64)
			(layers "B.Cu" "B.Mask" "B.Paste")
			(roundrect_rratio 0.25)
			(net 17 "+3V3")
			(pintype "passive")
		)
	)
	(footprint "antmicro-footprints:R_0201"
		(layer "B.Cu")
		(at 146.64 95.02 90)
		(descr "Resistor SMD 0201")
		(tags "resistor SMD 0201")
		(property "Reference" "R6"
			(at -3.77 -0.05 270)
			(layer "B.SilkS")
			(effects
				(font
					(size 0.7 0.7)
					(thickness 0.15)
				)
				(justify right top mirror)
			)
		)
		(property "Value" "R_0R_0201"
			(at 0 -1.25 90)
			(layer "B.Fab")
			(effects
				(font
					(size 0.7 0.7)
					(thickness 0.15)
				)
				(justify right top mirror)
			)
		)
		(property "Datasheet" "https://www.bourns.com/docs/product-datasheets/cr.pdf"
			(at 0 0 90)
			(layer "B.Fab")
			(hide yes)
			(effects
				(font
					(size 1.27 1.27)
					(thickness 0.15)
				)
				(justify mirror)
			)
		)
		(property "Description" "SMD Chip Resistor"
			(at 0 0 90)
			(layer "B.Fab")
			(hide yes)
			(effects
				(font
					(size 1.27 1.27)
					(thickness 0.15)
				)
				(justify mirror)
			)
		)
		(property "MPN" "CR0201-FX-0R00GLF"
			(at 0 0 270)
			(unlocked yes)
			(layer "B.Fab")
			(hide yes)
			(effects
				(font
					(size 1 1)
					(thickness 0.15)
				)
				(justify mirror)
			)
		)
		(property "Manufacturer" "Bourns"
			(at 0 0 270)
			(unlocked yes)
			(layer "B.Fab")
			(hide yes)
			(effects
				(font
					(size 1 1)
					(thickness 0.15)
				)
				(justify mirror)
			)
		)
		(property "License" "Apache-2.0"
			(at 0 0 270)
			(unlocked yes)
			(layer "B.Fab")
			(hide yes)
			(effects
				(font
					(size 1 1)
					(thickness 0.15)
				)
				(justify mirror)
			)
		)
		(property "Author" "Antmicro"
			(at 0 0 270)
			(unlocked yes)
			(layer "B.Fab")
			(hide yes)
			(effects
				(font
					(size 1 1)
					(thickness 0.15)
				)
				(justify mirror)
			)
		)
		(property "Val" "0R"
			(at 0 0 270)
			(unlocked yes)
			(layer "B.Fab")
			(hide yes)
			(effects
				(font
					(size 1 1)
					(thickness 0.15)
				)
				(justify mirror)
			)
		)
		(property "Tolerance" "1%"
			(at 0 0 270)
			(unlocked yes)
			(layer "B.Fab")
			(hide yes)
			(effects
				(font
					(size 1 1)
					(thickness 0.15)
				)
				(justify mirror)
			)
		)
		(sheetname "/")
		(sheetfile "antmicro-m2-oculink-adapter-hw.kicad_sch")
		(attr smd)
		(fp_rect
			(start -0.7 0.35)
			(end 0.7 -0.35)
			(stroke
				(width 0.05)
				(type default)
			)
			(fill no)
			(layer "B.CrtYd")
		)
		(fp_rect
			(start -0.3 0.15)
			(end 0.298 -0.148)
			(stroke
				(width 0.15)
				(type solid)
			)
			(fill no)
			(layer "B.Fab")
		)
		(fp_text user "Author: Antmicro"
			(at -0.71 -5.25 90)
			(layer "B.Fab")
			(effects
				(font
					(size 0.7 0.7)
					(thickness 0.15)
				)
				(justify right top mirror)
			)
		)
		(fp_text user "License: Apache-2.0"
			(at -0.71 -4.25 90)
			(layer "B.Fab")
			(effects
				(font
					(size 0.7 0.7)
					(thickness 0.15)
				)
				(justify right top mirror)
			)
		)
		(fp_text user "${REFERENCE}"
			(at -0.71 -3.25 90)
			(layer "B.Fab")
			(effects
				(font
					(size 0.7 0.7)
					(thickness 0.15)
				)
				(justify right top mirror)
			)
		)
		(pad "" smd roundrect
			(at -0.346 0 90)
			(size 0.318 0.36)
			(layers "B.Paste")
			(roundrect_rratio 0.25)
		)
		(pad "" smd roundrect
			(at 0.344 0 90)
			(size 0.318 0.36)
			(layers "B.Paste")
			(roundrect_rratio 0.25)
		)
		(pad "1" smd roundrect
			(at -0.32 0 90)
			(size 0.46 0.4)
			(layers "B.Cu" "B.Mask")
			(roundrect_rratio 0.25)
			(net 12 "/PCIe_{REF0}_R.CK-")
			(pintype "passive")
		)
		(pad "2" smd roundrect
			(at 0.32 0 90)
			(size 0.46 0.4)
			(layers "B.Cu" "B.Mask")
			(roundrect_rratio 0.25)
			(net 38 "/PCIe_{REF0}.CK-")
			(pintype "passive")
		)
	)
	(footprint "antmicro-footprints:R_0201"
		(layer "B.Cu")
		(at 144.22 94.75 -90)
		(descr "Resistor SMD 0201")
		(tags "resistor SMD 0201")
		(property "Reference" "R9"
			(at 0.84 -0.45 90)
			(layer "B.SilkS")
			(effects
				(font
					(size 0.7 0.7)
					(thickness 0.15)
				)
				(justify left bottom mirror)
			)
		)
		(property "Value" "R_0R_0201"
			(at 0 -1.249999 90)
			(layer "B.Fab")
			(effects
				(font
					(size 0.7 0.7)
					(thickness 0.15)
				)
				(justify left bottom mirror)
			)
		)
		(property "Datasheet" "https://www.bourns.com/docs/product-datasheets/cr.pdf"
			(at 0 0 90)
			(layer "B.Fab")
			(hide yes)
			(effects
				(font
					(size 1.27 1.27)
					(thickness 0.15)
				)
				(justify mirror)
			)
		)
		(property "Description" "SMD Chip Resistor"
			(at 0 0 90)
			(layer "B.Fab")
			(hide yes)
			(effects
				(font
					(size 1.27 1.27)
					(thickness 0.15)
				)
				(justify mirror)
			)
		)
		(property "MPN" "CR0201-FX-0R00GLF"
			(at 0 0 90)
			(unlocked yes)
			(layer "B.Fab")
			(hide yes)
			(effects
				(font
					(size 1 1)
					(thickness 0.15)
				)
				(justify mirror)
			)
		)
		(property "Manufacturer" "Bourns"
			(at 0 0 90)
			(unlocked yes)
			(layer "B.Fab")
			(hide yes)
			(effects
				(font
					(size 1 1)
					(thickness 0.15)
				)
				(justify mirror)
			)
		)
		(property "License" "Apache-2.0"
			(at 0 0 90)
			(unlocked yes)
			(layer "B.Fab")
			(hide yes)
			(effects
				(font
					(size 1 1)
					(thickness 0.15)
				)
				(justify mirror)
			)
		)
		(property "Author" "Antmicro"
			(at 0 0 90)
			(unlocked yes)
			(layer "B.Fab")
			(hide yes)
			(effects
				(font
					(size 1 1)
					(thickness 0.15)
				)
				(justify mirror)
			)
		)
		(property "Val" "0R"
			(at 0 0 90)
			(unlocked yes)
			(layer "B.Fab")
			(hide yes)
			(effects
				(font
					(size 1 1)
					(thickness 0.15)
				)
				(justify mirror)
			)
		)
		(property "Tolerance" "1%"
			(at 0 0 90)
			(unlocked yes)
			(layer "B.Fab")
			(hide yes)
			(effects
				(font
					(size 1 1)
					(thickness 0.15)
				)
				(justify mirror)
			)
		)
		(sheetname "/")
		(sheetfile "antmicro-m2-oculink-adapter-hw.kicad_sch")
		(attr smd dnp)
		(fp_rect
			(start -0.7 0.35)
			(end 0.7 -0.35)
			(stroke
				(width 0.05)
				(type default)
			)
			(fill no)
			(layer "B.CrtYd")
		)
		(fp_rect
			(start -0.3 0.15)
			(end 0.298 -0.148)
			(stroke
				(width 0.15)
				(type solid)
			)
			(fill no)
			(layer "B.Fab")
		)
		(fp_text user "License: Apache-2.0"
			(at -0.71 -4.25 90)
			(layer "B.Fab")
			(effects
				(font
					(size 0.7 0.7)
					(thickness 0.15)
				)
				(justify left bottom mirror)
			)
		)
		(fp_text user "${REFERENCE}"
			(at -0.71 -3.25 90)
			(layer "B.Fab")
			(effects
				(font
					(size 0.7 0.7)
					(thickness 0.15)
				)
				(justify left bottom mirror)
			)
		)
		(fp_text user "Author: Antmicro"
			(at -0.71 -5.25 90)
			(layer "B.Fab")
			(effects
				(font
					(size 0.7 0.7)
					(thickness 0.15)
				)
				(justify left bottom mirror)
			)
		)
		(pad "" smd roundrect
			(at -0.346 0 270)
			(size 0.318 0.36)
			(layers "B.Paste")
			(roundrect_rratio 0.25)
		)
		(pad "" smd roundrect
			(at 0.344 0 270)
			(size 0.318 0.36)
			(layers "B.Paste")
			(roundrect_rratio 0.25)
		)
		(pad "1" smd roundrect
			(at -0.32 0 270)
			(size 0.46 0.4)
			(layers "B.Cu" "B.Mask")
			(roundrect_rratio 0.25)
			(net 24 "/~{WAKEC}")
			(pintype "passive")
		)
		(pad "2" smd roundrect
			(at 0.32 0 270)
			(size 0.46 0.4)
			(layers "B.Cu" "B.Mask")
			(roundrect_rratio 0.25)
			(net 51 "/~{WAKE_C}_alt")
			(pintype "passive")
		)
	)
	(footprint "antmicro-footprints:R_0201"
		(layer "B.Cu")
		(at 145.93 95.02 90)
		(descr "Resistor SMD 0201")
		(tags "resistor SMD 0201")
		(property "Reference" "R4"
			(at -3.75 -0.64 270)
			(layer "B.SilkS")
			(effects
				(font
					(size 0.7 0.7)
					(thickness 0.15)
				)
				(justify right top mirror)
			)
		)
		(property "Value" "R_0R_0201"
			(at 0 -1.25 90)
			(layer "B.Fab")
			(effects
				(font
					(size 0.7 0.7)
					(thickness 0.15)
				)
				(justify right top mirror)
			)
		)
		(property "Datasheet" "https://www.bourns.com/docs/product-datasheets/cr.pdf"
			(at 0 0 90)
			(layer "B.Fab")
			(hide yes)
			(effects
				(font
					(size 1.27 1.27)
					(thickness 0.15)
				)
				(justify mirror)
			)
		)
		(property "Description" "SMD Chip Resistor"
			(at 0 0 90)
			(layer "B.Fab")
			(hide yes)
			(effects
				(font
					(size 1.27 1.27)
					(thickness 0.15)
				)
				(justify mirror)
			)
		)
		(property "MPN" "CR0201-FX-0R00GLF"
			(at 0 0 270)
			(unlocked yes)
			(layer "B.Fab")
			(hide yes)
			(effects
				(font
					(size 1 1)
					(thickness 0.15)
				)
				(justify mirror)
			)
		)
		(property "Manufacturer" "Bourns"
			(at 0 0 270)
			(unlocked yes)
			(layer "B.Fab")
			(hide yes)
			(effects
				(font
					(size 1 1)
					(thickness 0.15)
				)
				(justify mirror)
			)
		)
		(property "License" "Apache-2.0"
			(at 0 0 270)
			(unlocked yes)
			(layer "B.Fab")
			(hide yes)
			(effects
				(font
					(size 1 1)
					(thickness 0.15)
				)
				(justify mirror)
			)
		)
		(property "Author" "Antmicro"
			(at 0 0 270)
			(unlocked yes)
			(layer "B.Fab")
			(hide yes)
			(effects
				(font
					(size 1 1)
					(thickness 0.15)
				)
				(justify mirror)
			)
		)
		(property "Val" "0R"
			(at 0 0 270)
			(unlocked yes)
			(layer "B.Fab")
			(hide yes)
			(effects
				(font
					(size 1 1)
					(thickness 0.15)
				)
				(justify mirror)
			)
		)
		(property "Tolerance" "1%"
			(at 0 0 270)
			(unlocked yes)
			(layer "B.Fab")
			(hide yes)
			(effects
				(font
					(size 1 1)
					(thickness 0.15)
				)
				(justify mirror)
			)
		)
		(sheetname "/")
		(sheetfile "antmicro-m2-oculink-adapter-hw.kicad_sch")
		(attr smd)
		(fp_rect
			(start -0.7 0.35)
			(end 0.7 -0.35)
			(stroke
				(width 0.05)
				(type default)
			)
			(fill no)
			(layer "B.CrtYd")
		)
		(fp_rect
			(start -0.3 0.15)
			(end 0.298 -0.148)
			(stroke
				(width 0.15)
				(type solid)
			)
			(fill no)
			(layer "B.Fab")
		)
		(fp_text user "${REFERENCE}"
			(at -0.71 -3.25 90)
			(layer "B.Fab")
			(effects
				(font
					(size 0.7 0.7)
					(thickness 0.15)
				)
				(justify right top mirror)
			)
		)
		(fp_text user "License: Apache-2.0"
			(at -0.71 -4.25 90)
			(layer "B.Fab")
			(effects
				(font
					(size 0.7 0.7)
					(thickness 0.15)
				)
				(justify right top mirror)
			)
		)
		(fp_text user "Author: Antmicro"
			(at -0.71 -5.25 90)
			(layer "B.Fab")
			(effects
				(font
					(size 0.7 0.7)
					(thickness 0.15)
				)
				(justify right top mirror)
			)
		)
		(pad "" smd roundrect
			(at -0.346 0 90)
			(size 0.318 0.36)
			(layers "B.Paste")
			(roundrect_rratio 0.25)
		)
		(pad "" smd roundrect
			(at 0.344 0 90)
			(size 0.318 0.36)
			(layers "B.Paste")
			(roundrect_rratio 0.25)
		)
		(pad "1" smd roundrect
			(at -0.32 0 90)
			(size 0.46 0.4)
			(layers "B.Cu" "B.Mask")
			(roundrect_rratio 0.25)
			(net 13 "/PCIe_{REF0}_R.CK+")
			(pintype "passive")
		)
		(pad "2" smd roundrect
			(at 0.32 0 90)
			(size 0.46 0.4)
			(layers "B.Cu" "B.Mask")
			(roundrect_rratio 0.25)
			(net 36 "/PCIe_{REF0}.CK+")
			(pintype "passive")
		)
	)
	(footprint "antmicro-footprints:R_0201"
		(layer "B.Cu")
		(at 145.93 94.38 90)
		(descr "Resistor SMD 0201")
		(tags "resistor SMD 0201")
		(property "Reference" "R3"
			(at -2.9 -0.64 270)
			(layer "B.SilkS")
			(effects
				(font
					(size 0.7 0.7)
					(thickness 0.15)
				)
				(justify right top mirror)
			)
		)
		(property "Value" "R_0R_0201"
			(at 0 -1.25 90)
			(layer "B.Fab")
			(effects
				(font
					(size 0.7 0.7)
					(thickness 0.15)
				)
				(justify right top mirror)
			)
		)
		(property "Datasheet" "https://www.bourns.com/docs/product-datasheets/cr.pdf"
			(at 0 0 90)
			(layer "B.Fab")
			(hide yes)
			(effects
				(font
					(size 1.27 1.27)
					(thickness 0.15)
				)
				(justify mirror)
			)
		)
		(property "Description" "SMD Chip Resistor"
			(at 0 0 90)
			(layer "B.Fab")
			(hide yes)
			(effects
				(font
					(size 1.27 1.27)
					(thickness 0.15)
				)
				(justify mirror)
			)
		)
		(property "MPN" "CR0201-FX-0R00GLF"
			(at 0 0 270)
			(unlocked yes)
			(layer "B.Fab")
			(hide yes)
			(effects
				(font
					(size 1 1)
					(thickness 0.15)
				)
				(justify mirror)
			)
		)
		(property "Manufacturer" "Bourns"
			(at 0 0 270)
			(unlocked yes)
			(layer "B.Fab")
			(hide yes)
			(effects
				(font
					(size 1 1)
					(thickness 0.15)
				)
				(justify mirror)
			)
		)
		(property "License" "Apache-2.0"
			(at 0 0 270)
			(unlocked yes)
			(layer "B.Fab")
			(hide yes)
			(effects
				(font
					(size 1 1)
					(thickness 0.15)
				)
				(justify mirror)
			)
		)
		(property "Author" "Antmicro"
			(at 0 0 270)
			(unlocked yes)
			(layer "B.Fab")
			(hide yes)
			(effects
				(font
					(size 1 1)
					(thickness 0.15)
				)
				(justify mirror)
			)
		)
		(property "Val" "0R"
			(at 0 0 270)
			(unlocked yes)
			(layer "B.Fab")
			(hide yes)
			(effects
				(font
					(size 1 1)
					(thickness 0.15)
				)
				(justify mirror)
			)
		)
		(property "Tolerance" "1%"
			(at 0 0 270)
			(unlocked yes)
			(layer "B.Fab")
			(hide yes)
			(effects
				(font
					(size 1 1)
					(thickness 0.15)
				)
				(justify mirror)
			)
		)
		(sheetname "/")
		(sheetfile "antmicro-m2-oculink-adapter-hw.kicad_sch")
		(attr smd dnp)
		(fp_rect
			(start -0.7 0.35)
			(end 0.7 -0.35)
			(stroke
				(width 0.05)
				(type default)
			)
			(fill no)
			(layer "B.CrtYd")
		)
		(fp_rect
			(start -0.3 0.15)
			(end 0.298 -0.148)
			(stroke
				(width 0.15)
				(type solid)
			)
			(fill no)
			(layer "B.Fab")
		)
		(fp_text user "${REFERENCE}"
			(at -0.71 -3.25 90)
			(layer "B.Fab")
			(effects
				(font
					(size 0.7 0.7)
					(thickness 0.15)
				)
				(justify right top mirror)
			)
		)
		(fp_text user "Author: Antmicro"
			(at -0.71 -5.25 90)
			(layer "B.Fab")
			(effects
				(font
					(size 0.7 0.7)
					(thickness 0.15)
				)
				(justify right top mirror)
			)
		)
		(fp_text user "License: Apache-2.0"
			(at -0.71 -4.25 90)
			(layer "B.Fab")
			(effects
				(font
					(size 0.7 0.7)
					(thickness 0.15)
				)
				(justify right top mirror)
			)
		)
		(pad "" smd roundrect
			(at -0.346 0 90)
			(size 0.318 0.36)
			(layers "B.Paste")
			(roundrect_rratio 0.25)
		)
		(pad "" smd roundrect
			(at 0.344 0 90)
			(size 0.318 0.36)
			(layers "B.Paste")
			(roundrect_rratio 0.25)
		)
		(pad "1" smd roundrect
			(at -0.32 0 90)
			(size 0.46 0.4)
			(layers "B.Cu" "B.Mask")
			(roundrect_rratio 0.25)
			(net 36 "/PCIe_{REF0}.CK+")
			(pintype "passive")
		)
		(pad "2" smd roundrect
			(at 0.32 0 90)
			(size 0.46 0.4)
			(layers "B.Cu" "B.Mask")
			(roundrect_rratio 0.25)
			(net 23 "/~{PERSTC}")
			(pintype "passive")
		)
	)
)
